(kicad_pcb
	(version 20241229)
	(generator "pcbnew")
	(generator_version "9.0")
	(general
		(thickness 1.62)
		(legacy_teardrops no)
	)
	(paper "A3")
	(title_block
		(title "COM Express 7 Baseboard")
		(date "2025-02-04")
		(rev "1.1.2")
		(company "Antmicro Ltd")
		(comment 1 "www.antmicro.com")
		(comment 9 "footprints 466-468 of 802")
	)
	(layers
		(0 "F.Cu" signal)
		(4 "In1.Cu" signal)
		(6 "In2.Cu" signal)
		(8 "In3.Cu" signal)
		(10 "In4.Cu" signal)
		(12 "In5.Cu" signal)
		(14 "In6.Cu" signal)
		(2 "B.Cu" signal)
		(9 "F.Adhes" user "F.Adhesive")
		(11 "B.Adhes" user "B.Adhesive")
		(13 "F.Paste" user)
		(15 "B.Paste" user)
		(5 "F.SilkS" user "F.Silkscreen")
		(7 "B.SilkS" user "B.Silkscreen")
		(1 "F.Mask" user)
		(3 "B.Mask" user)
		(17 "Dwgs.User" user "User.Drawings")
		(19 "Cmts.User" user "User.Comments")
		(21 "Eco1.User" user "User.Eco1")
		(23 "Eco2.User" user "User.Eco2")
		(25 "Edge.Cuts" user)
		(27 "Margin" user)
		(31 "F.CrtYd" user "F.Courtyard")
		(29 "B.CrtYd" user "B.Courtyard")
		(35 "F.Fab" user)
		(33 "B.Fab" user)
	)
	(footprint "antmicro-footprints:R_0201"
		(layer "F.Cu")
		(at 155.572 147.935 -90)
		(descr "Resistor SMD 0201")
		(tags "resistor SMD 0201")
		(property "Reference" "R251"
			(at 6.495 -0.278 270)
			(layer "F.SilkS")
			(effects
				(font
					(size 0.7 0.7)
					(thickness 0.15)
				)
				(justify left bottom)
			)
		)
		(property "Value" "R_0R_0201"
			(at 0 1.25 270)
			(layer "F.Fab")
			(effects
				(font
					(size 0.7 0.7)
					(thickness 0.15)
				)
				(justify left bottom)
			)
		)
		(property "Datasheet" "https://www.bourns.com/docs/product-datasheets/cr.pdf"
			(at 0 0 270)
			(layer "F.Fab")
			(hide yes)
			(effects
				(font
					(size 1.27 1.27)
					(thickness 0.15)
				)
			)
		)
		(property "Author" "Antmicro"
			(at 7.637 303.507 0)
			(layer "F.Fab")
			(hide yes)
			(effects
				(font
					(size 1 1)
					(thickness 0.15)
				)
			)
		)
		(property "License" "Apache-2.0"
			(at 7.637 303.507 0)
			(layer "F.Fab")
			(hide yes)
			(effects
				(font
					(size 1 1)
					(thickness 0.15)
				)
			)
		)
		(property "MPN" "CR0201-FX-0R00GLF"
			(at 7.637 303.507 0)
			(layer "F.Fab")
			(hide yes)
			(effects
				(font
					(size 1 1)
					(thickness 0.15)
				)
			)
		)
		(property "Manufacturer" "Bourns"
			(at 7.637 303.507 0)
			(layer "F.Fab")
			(hide yes)
			(effects
				(font
					(size 1 1)
					(thickness 0.15)
				)
			)
		)
		(property "Tolerance" "1%"
			(at 7.637 303.507 0)
			(layer "F.Fab")
			(hide yes)
			(effects
				(font
					(size 1 1)
					(thickness 0.15)
				)
			)
		)
		(property "Val" "0R"
			(at 7.637 303.507 0)
			(layer "F.Fab")
			(hide yes)
			(effects
				(font
					(size 1 1)
					(thickness 0.15)
				)
			)
		)
		(sheetname "KR to SFI #1")
		(sheetfile "kr_sfi.kicad_sch")
		(attr smd dnp)
		(fp_rect
			(start -0.7 -0.35)
			(end 0.7 0.35)
			(stroke
				(width 0.05)
				(type default)
			)
			(fill no)
			(layer "F.CrtYd")
		)
		(fp_rect
			(start -0.3 -0.15)
			(end 0.298 0.148)
			(stroke
				(width 0.15)
				(type solid)
			)
			(fill no)
			(layer "F.Fab")
		)
		(pad "" smd roundrect
			(at -0.346 0 270)
			(size 0.318 0.36)
			(layers "F.Paste")
			(roundrect_rratio 0.25)
			(teardrops
				(best_length_ratio 0.2)
				(max_length 1)
				(best_width_ratio 0.9)
				(max_width 2)
				(curved_edges yes)
				(filter_ratio 0.9)
				(enabled yes)
				(allow_two_segments yes)
				(prefer_zone_connections yes)
			)
		)
		(pad "" smd roundrect
			(at 0.344 0 270)
			(size 0.318 0.36)
			(layers "F.Paste")
			(roundrect_rratio 0.25)
			(teardrops
				(best_length_ratio 0.2)
				(max_length 1)
				(best_width_ratio 0.9)
				(max_width 2)
				(curved_edges yes)
				(filter_ratio 0.9)
				(enabled yes)
				(allow_two_segments yes)
				(prefer_zone_connections yes)
			)
		)
		(pad "1" smd roundrect
			(at -0.32 0 270)
			(size 0.46 0.4)
			(layers "F.Cu" "F.Mask")
			(roundrect_rratio 0.25)
			(net 111 "/2xSFP+/10GKR_SFP0.TX+")
			(pintype "passive")
			(teardrops
				(best_length_ratio 0.2)
				(max_length 1)
				(best_width_ratio 0.9)
				(max_width 2)
				(curved_edges yes)
				(filter_ratio 0.9)
				(enabled yes)
				(allow_two_segments yes)
				(prefer_zone_connections yes)
			)
		)
		(pad "2" smd roundrect
			(at 0.32 0 270)
			(size 0.46 0.4)
			(layers "F.Cu" "F.Mask")
			(roundrect_rratio 0.25)
			(net 954 "/2xSFP+/KR to SFI #1/BYP_TX+")
			(pintype "passive")
			(teardrops
				(best_length_ratio 0.2)
				(max_length 1)
				(best_width_ratio 0.9)
				(max_width 2)
				(curved_edges yes)
				(filter_ratio 0.9)
				(enabled yes)
				(allow_two_segments yes)
				(prefer_zone_connections yes)
			)
		)
	)
	(footprint "antmicro-footprints:MicroSD_Wurth_693071020811"
		(layer "F.Cu")
		(at 101.935 136.76 -90)
		(descr "SMT MICRO SD CARD CONNECTOR")
		(property "Reference" "J15"
			(at 9.2 4.735 180)
			(layer "F.SilkS")
			(effects
				(font
					(size 0.7 0.7)
					(thickness 0.15)
				)
				(justify right bottom)
			)
		)
		(property "Value" "MicroSD_693071020811"
			(at 0 8.9 90)
			(layer "F.Fab")
			(effects
				(font
					(size 0.7 0.7)
					(thickness 0.15)
				)
				(justify right bottom)
			)
		)
		(property "Datasheet" "https://www.we-online.com/catalog/datasheet/693071020811.pdf"
			(at 0 0 270)
			(layer "F.Fab")
			(hide yes)
			(effects
				(font
					(size 1.27 1.27)
					(thickness 0.15)
				)
			)
		)
		(property "Author" "Antmicro"
			(at -34.825 238.695 0)
			(layer "F.Fab")
			(hide yes)
			(effects
				(font
					(size 1 1)
					(thickness 0.15)
				)
			)
		)
		(property "License" "Apache-2.0"
			(at -34.825 238.695 0)
			(layer "F.Fab")
			(hide yes)
			(effects
				(font
					(size 1 1)
					(thickness 0.15)
				)
			)
		)
		(property "MPN" "693071020811"
			(at -34.825 238.695 0)
			(layer "F.Fab")
			(hide yes)
			(effects
				(font
					(size 1 1)
					(thickness 0.15)
				)
			)
		)
		(property "Manufacturer" "Würth Elektronik"
			(at -34.825 238.695 0)
			(layer "F.Fab")
			(hide yes)
			(effects
				(font
					(size 1 1)
					(thickness 0.15)
				)
			)
		)
		(sheetname "SD card")
		(sheetfile "sd_card.kicad_sch")
		(attr smd)
		(fp_line
			(start -7.35 1.432)
			(end -7.35 -5.267)
			(stroke
				(width 0.15)
				(type solid)
			)
			(layer "F.SilkS")
		)
		(fp_line
			(start 7.35 1.432)
			(end 7.35 -5.267)
			(stroke
				(width 0.15)
				(type solid)
			)
			(layer "F.SilkS")
		)
		(fp_line
			(start 6.201 -7.148)
			(end 2.801 -7.148)
			(stroke
				(width 0.15)
				(type solid)
			)
			(layer "F.SilkS")
		)
		(fp_circle
			(center 2.85 -7.9)
			(end 2.9 -7.9)
			(stroke
				(width 0.15)
				(type solid)
			)
			(fill yes)
			(layer "F.SilkS")
		)
		(fp_line
			(start -7.55 7.7)
			(end -7.55 4.55)
			(stroke
				(width 0.05)
				(type solid)
			)
			(layer "F.CrtYd")
		)
		(fp_line
			(start 7.5 7.7)
			(end -7.55 7.7)
			(stroke
				(width 0.05)
				(type solid)
			)
			(layer "F.CrtYd")
		)
		(fp_line
			(start 7.5 7.7)
			(end 7.5 4.55)
			(stroke
				(width 0.05)
				(type solid)
			)
			(layer "F.CrtYd")
		)
		(fp_line
			(start -8.7 4.55)
			(end -7.55 4.55)
			(stroke
				(width 0.05)
				(type solid)
			)
			(layer "F.CrtYd")
		)
		(fp_line
			(start -8.7 4.55)
			(end -8.7 1.6)
			(stroke
				(width 0.05)
				(type solid)
			)
			(layer "F.CrtYd")
		)
		(fp_line
			(start 8.7 4.55)
			(end 7.5 4.55)
			(stroke
				(width 0.05)
				(type solid)
			)
			(layer "F.CrtYd")
		)
		(fp_line
			(start 8.7 4.55)
			(end 8.7 1.6)
			(stroke
				(width 0.05)
				(type solid)
			)
			(layer "F.CrtYd")
		)
		(fp_line
			(start -7.55 1.6)
			(end -8.7 1.6)
			(stroke
				(width 0.05)
				(type solid)
			)
			(layer "F.CrtYd")
		)
		(fp_line
			(start 7.5 1.6)
			(end 8.7 1.6)
			(stroke
				(width 0.05)
				(type solid)
			)
			(layer "F.CrtYd")
		)
		(fp_line
			(start 7.5 1.6)
			(end 7.5 -5.45)
			(stroke
				(width 0.05)
				(type solid)
			)
			(layer "F.CrtYd")
		)
		(fp_line
			(start -7.55 -5.45)
			(end -7.55 1.6)
			(stroke
				(width 0.05)
				(type solid)
			)
			(layer "F.CrtYd")
		)
		(fp_line
			(start -7.55 -5.45)
			(end -9.1 -5.45)
			(stroke
				(width 0.05)
				(type solid)
			)
			(layer "F.CrtYd")
		)
		(fp_line
			(start 7.5 -5.45)
			(end 8.4 -5.45)
			(stroke
				(width 0.05)
				(type solid)
			)
			(layer "F.CrtYd")
		)
		(fp_line
			(start -9.1 -7.6)
			(end -9.1 -5.45)
			(stroke
				(width 0.05)
				(type solid)
			)
			(layer "F.CrtYd")
		)
		(fp_line
			(start -9.1 -7.6)
			(end -7.05 -7.6)
			(stroke
				(width 0.05)
				(type solid)
			)
			(layer "F.CrtYd")
		)
		(fp_line
			(start 2.75 -7.6)
			(end 2.75 -8.7)
			(stroke
				(width 0.05)
				(type solid)
			)
			(layer "F.CrtYd")
		)
		(fp_line
			(start 8.4 -7.6)
			(end 8.4 -5.45)
			(stroke
				(width 0.05)
				(type solid)
			)
			(layer "F.CrtYd")
		)
		(fp_line
			(start 8.4 -7.6)
			(end 2.75 -7.6)
			(stroke
				(width 0.05)
				(type solid)
			)
			(layer "F.CrtYd")
		)
		(fp_line
			(start -7.05 -8.7)
			(end -7.05 -7.6)
			(stroke
				(width 0.05)
				(type solid)
			)
			(layer "F.CrtYd")
		)
		(fp_line
			(start -7.05 -8.7)
			(end 2.75 -8.7)
			(stroke
				(width 0.05)
				(type solid)
			)
			(layer "F.CrtYd")
		)
		(fp_line
			(start -7.35 7.502)
			(end 7.35 7.502)
			(stroke
				(width 0.15)
				(type solid)
			)
			(layer "F.Fab")
		)
		(fp_line
			(start 7.35 7.353)
			(end 7.35 -7.148)
			(stroke
				(width 0.15)
				(type solid)
			)
			(layer "F.Fab")
		)
		(fp_line
			(start -7.35 -7.148)
			(end -7.35 7.353)
			(stroke
				(width 0.15)
				(type solid)
			)
			(layer "F.Fab")
		)
		(fp_line
			(start 7.35 -7.148)
			(end -7.35 -7.148)
			(stroke
				(width 0.15)
				(type solid)
			)
			(layer "F.Fab")
		)
		(pad "" np_thru_hole circle
			(at -4.95 3.485 270)
			(size 1 1)
			(drill 1)
			(layers "F&B.Cu" "*.Mask")
		)
		(pad "" np_thru_hole oval
			(at 3.05 3.485 270)
			(size 1.7 1)
			(drill oval 1.7 1)
			(layers "F&B.Cu" "*.Mask")
		)
		(pad "1" smd rect
			(at 2.25 -7.57 270)
			(size 0.7 1.9)
			(layers "F.Cu" "F.Mask" "F.Paste")
			(net 323 "/Com Express 7 Interfaces/SDIO.DAT2")
			(pinfunction "DAT2")
			(pintype "bidirectional")
			(teardrops
				(best_length_ratio 0.2)
				(max_length 1)
				(best_width_ratio 0.9)
				(max_width 2)
				(curved_edges yes)
				(filter_ratio 0.9)
				(enabled yes)
				(allow_two_segments yes)
				(prefer_zone_connections yes)
			)
		)
		(pad "2" smd rect
			(at 1.15 -7.57 270)
			(size 0.7 1.9)
			(layers "F.Cu" "F.Mask" "F.Paste")
			(net 333 "/Com Express 7 Interfaces/SDIO.DAT3")
			(pinfunction "DAT3/CD")
			(pintype "bidirectional")
			(teardrops
				(best_length_ratio 0.2)
				(max_length 1)
				(best_width_ratio 0.9)
				(max_width 2)
				(curved_edges yes)
				(filter_ratio 0.9)
				(enabled yes)
				(allow_two_segments yes)
				(prefer_zone_connections yes)
			)
		)
		(pad "3" smd rect
			(at 0.05 -7.57 270)
			(size 0.7 1.9)
			(layers "F.Cu" "F.Mask" "F.Paste")
			(net 385 "/Com Express 7 Interfaces/SDIO.CMD")
			(pinfunction "CMD")
			(pintype "input")
			(teardrops
				(best_length_ratio 0.2)
				(max_length 1)
				(best_width_ratio 0.9)
				(max_width 2)
				(curved_edges yes)
				(filter_ratio 0.9)
				(enabled yes)
				(allow_two_segments yes)
				(prefer_zone_connections yes)
			)
		)
		(pad "4" smd rect
			(at -1.05 -7.57 270)
			(size 0.7 1.9)
			(layers "F.Cu" "F.Mask" "F.Paste")
			(net 2 "+3V3")
			(pinfunction "VDD")
			(pintype "power_in")
			(teardrops
				(best_length_ratio 0.2)
				(max_length 1)
				(best_width_ratio 0.9)
				(max_width 2)
				(curved_edges yes)
				(filter_ratio 0.9)
				(enabled yes)
				(allow_two_segments yes)
				(prefer_zone_connections yes)
			)
		)
		(pad "5" smd rect
			(at -2.15 -7.57 270)
			(size 0.7 1.9)
			(layers "F.Cu" "F.Mask" "F.Paste")
			(net 339 "/Com Express 7 Interfaces/SDIO.CLK")
			(pinfunction "CLK")
			(pintype "input")
			(teardrops
				(best_length_ratio 0.2)
				(max_length 1)
				(best_width_ratio 0.9)
				(max_width 2)
				(curved_edges yes)
				(filter_ratio 0.9)
				(enabled yes)
				(allow_two_segments yes)
				(prefer_zone_connections yes)
			)
		)
		(pad "6" smd rect
			(at -3.25 -7.57 270)
			(size 0.7 1.9)
			(layers "F.Cu" "F.Mask" "F.Paste")
			(net 1 "GND")
			(pinfunction "VSS")
			(pintype "passive")
			(teardrops
				(best_length_ratio 0.2)
				(max_length 1)
				(best_width_ratio 0.9)
				(max_width 2)
				(curved_edges yes)
				(filter_ratio 0.9)
				(enabled yes)
				(allow_two_segments yes)
				(prefer_zone_connections yes)
			)
		)
		(pad "7" smd rect
			(at -4.35 -7.57 270)
			(size 0.7 1.9)
			(layers "F.Cu" "F.Mask" "F.Paste")
			(net 321 "/Com Express 7 Interfaces/SDIO.DAT0")
			(pinfunction "DAT0")
			(pintype "input")
			(teardrops
				(best_length_ratio 0.2)
				(max_length 1)
				(best_width_ratio 0.9)
				(max_width 2)
				(curved_edges yes)
				(filter_ratio 0.9)
				(enabled yes)
				(allow_two_segments yes)
				(prefer_zone_connections yes)
			)
		)
		(pad "8" smd rect
			(at -5.45 -7.57 270)
			(size 0.7 1.9)
			(layers "F.Cu" "F.Mask" "F.Paste")
			(net 322 "/Com Express 7 Interfaces/SDIO.DAT1")
			(pinfunction "DAT1")
			(pintype "input")
			(teardrops
				(best_length_ratio 0.2)
				(max_length 1)
				(best_width_ratio 0.9)
				(max_width 2)
				(curved_edges yes)
				(filter_ratio 0.9)
				(enabled yes)
				(allow_two_segments yes)
				(prefer_zone_connections yes)
			)
		)
		(pad "9" smd rect
			(at -6.55 -7.57 270)
			(size 0.7 1.9)
			(layers "F.Cu" "F.Mask" "F.Paste")
			(net 531 "/Com Express 7 Interfaces/SD_CD")
			(pinfunction "CD_SW1")
			(pintype "passive")
			(teardrops
				(best_length_ratio 0.2)
				(max_length 1)
				(best_width_ratio 0.9)
				(max_width 2)
				(curved_edges yes)
				(filter_ratio 0.9)
				(enabled yes)
				(allow_two_segments yes)
				(prefer_zone_connections yes)
			)
		)
		(pad "SH" smd rect
			(at -8.1 -6.515 270)
			(size 1.7 1.8)
			(layers "F.Cu" "F.Mask" "F.Paste")
			(net 1 "GND")
			(pinfunction "SH")
			(pintype "passive")
			(teardrops
				(best_length_ratio 0.2)
				(max_length 1)
				(best_width_ratio 0.9)
				(max_width 2)
				(curved_edges yes)
				(filter_ratio 0.9)
				(enabled yes)
				(allow_two_segments yes)
				(prefer_zone_connections yes)
			)
		)
		(pad "SH" smd rect
			(at -7.85 3.08 270)
			(size 1.4 2.6)
			(layers "F.Cu" "F.Mask" "F.Paste")
			(net 1 "GND")
			(pinfunction "SH")
			(pintype "passive")
			(teardrops
				(best_length_ratio 0.2)
				(max_length 1)
				(best_width_ratio 0.9)
				(max_width 2)
				(curved_edges yes)
				(filter_ratio 0.9)
				(enabled yes)
				(allow_two_segments yes)
				(prefer_zone_connections yes)
			)
		)
		(pad "SH" smd rect
			(at 7.4 -6.515 270)
			(size 1.7 1.8)
			(layers "F.Cu" "F.Mask" "F.Paste")
			(net 1 "GND")
			(pinfunction "SH")
			(pintype "passive")
			(teardrops
				(best_length_ratio 0.2)
				(max_length 1)
				(best_width_ratio 0.9)
				(max_width 2)
				(curved_edges yes)
				(filter_ratio 0.9)
				(enabled yes)
				(allow_two_segments yes)
				(prefer_zone_connections yes)
			)
		)
		(pad "SH" smd rect
			(at 7.85 3.08 270)
			(size 1.4 2.6)
			(layers "F.Cu" "F.Mask" "F.Paste")
			(net 1 "GND")
			(pinfunction "SH")
			(pintype "passive")
			(teardrops
				(best_length_ratio 0.2)
				(max_length 1)
				(best_width_ratio 0.9)
				(max_width 2)
				(curved_edges yes)
				(filter_ratio 0.9)
				(enabled yes)
				(allow_two_segments yes)
				(prefer_zone_connections yes)
			)
		)
	)
	(footprint "antmicro-footprints:R_0402_1005Metric"
		(layer "F.Cu")
		(at 178.4 144 180)
		(descr "Resistor SMD 0402")
		(tags "resistor SMD 0402")
		(property "Reference" "R40"
			(at -2.95 -0.45 0)
			(layer "F.SilkS")
			(effects
				(font
					(size 0.7 0.7)
					(thickness 0.15)
				)
				(justify right bottom)
			)
		)
		(property "Value" "R_0R_0402"
			(at -1.011843 1.772046 0)
			(layer "F.Fab")
			(effects
				(font
					(size 0.7 0.7)
					(thickness 0.15)
				)
				(justify right bottom)
			)
		)
		(property "Datasheet" "https://industrial.panasonic.com/cdbs/www-data/pdf/RDA0000/AOA0000C301.pdf"
			(at 0 0 0)
			(layer "F.Fab")
			(hide yes)
			(effects
				(font
					(size 1.27 1.27)
					(thickness 0.15)
				)
			)
		)
		(property "Author" "Antmicro"
			(at 337.9 330.52 0)
			(layer "F.Fab")
			(hide yes)
			(effects
				(font
					(size 1 1)
					(thickness 0.15)
				)
			)
		)
		(property "Current" "1A"
			(at 337.9 330.52 0)
			(layer "F.Fab")
			(hide yes)
			(effects
				(font
					(size 1 1)
					(thickness 0.15)
				)
			)
		)
		(property "License" "Apache-2.0"
			(at 337.9 330.52 0)
			(layer "F.Fab")
			(hide yes)
			(effects
				(font
					(size 1 1)
					(thickness 0.15)
				)
			)
		)
		(property "MPN" "ERJ2GE0R00X"
			(at 337.9 330.52 0)
			(layer "F.Fab")
			(hide yes)
			(effects
				(font
					(size 1 1)
					(thickness 0.15)
				)
			)
		)
		(property "Manufacturer" "Panasonic"
			(at 337.9 330.52 0)
			(layer "F.Fab")
			(hide yes)
			(effects
				(font
					(size 1 1)
					(thickness 0.15)
				)
			)
		)
		(property "Public" "False"
			(at 337.9 330.52 0)
			(layer "F.Fab")
			(hide yes)
			(effects
				(font
					(size 1 1)
					(thickness 0.15)
				)
			)
		)
		(property "Tolerance" ""
			(at 337.9 330.52 0)
			(layer "F.Fab")
			(hide yes)
			(effects
				(font
					(size 1 1)
					(thickness 0.15)
				)
			)
		)
		(property "Val" "0R"
			(at 337.9 330.52 0)
			(layer "F.Fab")
			(hide yes)
			(effects
				(font
					(size 1 1)
					(thickness 0.15)
				)
			)
		)
		(sheetname "2xSFP+")
		(sheetfile "2xSFP+.kicad_sch")
		(attr smd)
		(fp_rect
			(start -0.925 -0.47)
			(end 0.925 0.47)
			(stroke
				(width 0.05)
				(type default)
			)
			(fill no)
			(layer "F.CrtYd")
		)
		(fp_rect
			(start -0.5 -0.25)
			(end 0.5 0.25)
			(stroke
				(width 0.15)
				(type solid)
			)
			(fill no)
			(layer "F.Fab")
		)
		(pad "1" smd roundrect
			(at -0.48 0 180)
			(size 0.59 0.64)
			(layers "F.Cu" "F.Mask" "F.Paste")
			(roundrect_rratio 0.25)
			(net 424 "/2xSFP+/I2C_{SFP1}.SDA")
			(pintype "passive")
			(teardrops
				(best_length_ratio 0.2)
				(max_length 1)
				(best_width_ratio 0.9)
				(max_width 2)
				(curved_edges yes)
				(filter_ratio 0.9)
				(enabled yes)
				(allow_two_segments yes)
				(prefer_zone_connections yes)
			)
		)
		(pad "2" smd roundrect
			(at 0.48 0 180)
			(size 0.59 0.64)
			(layers "F.Cu" "F.Mask" "F.Paste")
			(roundrect_rratio 0.25)
			(net 874 "/2xSFP+/SDA1")
			(pintype "passive")
			(teardrops
				(best_length_ratio 0.2)
				(max_length 1)
				(best_width_ratio 0.9)
				(max_width 2)
				(curved_edges yes)
				(filter_ratio 0.9)
				(enabled yes)
				(allow_two_segments yes)
				(prefer_zone_connections yes)
			)
		)
	)
)
